FILE_TYPE=LIBRARY_PARTS;
TIME=' Created/Modified on Wed Sep 30 13:04:35 2009' ;
primitive '74LVC1G02GW';
  pin
    'B':
      PIN_NUMBER='(1)';
      INPUT_LOAD='(-0.01,0.01)';
    'A':
      PIN_NUMBER='(2)';
      INPUT_LOAD='(-0.01,0.01)';
    'Y':
      PIN_NUMBER='(4)';
      OUTPUT_LOAD='(1.0,-1.0)';
    'VCC':
      PIN_NUMBER='(5)';
      PINUSE='POWER';
    'GND':
      PIN_NUMBER='(3)';
      PINUSE='POWER';
  end_pin;
  body
    CLASS='IC';
    PART_NAME='74LVC1G02GW';
    PHYS_DES_PREFIX='U';
  end_body;
end_primitive;
END.
